# T6G (Grand Teton) — schematic netlist excerpt (pin names and nets, part order shuffled) for the footprints in the layout excerpt that follows; sources: Cadence DE-HDL packaged netlist, KiCad conversion of 04192023_DAF0TMB3IC0_F0TG_MB_C_brd_V02_OCP.brd

C373  Q_CAP  4.7UF 6.3V 20% X6S  pkg 0402  page 345 : A = P1V8_CPU1_RT_1D ; B = GND
C907  Q_CAP_DIFFBUS  DIFF BUS_0.22UF 6.3V 20% X6S  pkg C0201  page 63 : \1\ = P5E_CPU0_P0_TX_C_DP<13> ; \2\ = P5E_CPU0_P0_TX_DP<13>
R1434  Q_RES  1K 1% EMPTY  pkg 0201LF  page 353 : A = P1V8_CPU1_RT_1D ; B = RXDET_BYP_RT_CPU1_P3

(kicad_pcb
	(version 20260206)
	(generator "pcbnew")
	(generator_version "10.0")
	(general
		(thickness 1.6)
		(legacy_teardrops no)
	)
	(paper "A4")
	(title_block
		(title "04192023_DAF0TMB3IC0_F0TG_MB_C_brd_V02_OCP.brd")
		(comment 1 "Grand Teton / footprints 775-777 of 8354")
	)
	(layers
		(0 "F.Cu" signal "TOP")
		(4 "In1.Cu" signal "GND")
		(6 "In2.Cu" signal "IN1")
		(8 "In3.Cu" signal "GND1")
		(10 "In4.Cu" signal "IN2")
		(12 "In5.Cu" signal "GND2")
		(14 "In6.Cu" signal "IN3")
		(16 "In7.Cu" signal "GND3")
		(18 "In8.Cu" signal "VCC")
		(20 "In9.Cu" signal "VCC1")
		(22 "In10.Cu" signal "GND4")
		(24 "In11.Cu" signal "IN4")
		(26 "In12.Cu" signal "GND5")
		(28 "In13.Cu" signal "IN5")
		(30 "In14.Cu" signal "GND6")
		(32 "In15.Cu" signal "IN6")
		(34 "In16.Cu" signal "GND7")
		(2 "B.Cu" signal "BOTTOM")
		(9 "F.Adhes" user "F.Adhesive")
		(11 "B.Adhes" user "B.Adhesive")
		(13 "F.Paste" user "Package Geometry/Pastemask Top")
		(15 "B.Paste" user "Package Geometry/Pastemask Bottom")
		(5 "F.SilkS" user "Ref Des/Silkscreen Top")
		(7 "B.SilkS" user "Ref Des/Silkscreen Bottom")
		(1 "F.Mask" user "Board Geometry/Soldermask Top")
		(3 "B.Mask" user "Board Geometry/Soldermask Bottom")
		(17 "Dwgs.User" user "User.Drawings")
		(19 "Cmts.User" user "User.Comments")
		(21 "Eco1.User" user "User.Eco1")
		(23 "Eco2.User" user "User.Eco2")
		(25 "Edge.Cuts" user "Board Geometry/Outline")
		(27 "Margin" user)
		(31 "F.CrtYd" user "Package Geometry/Place Bound Top")
		(29 "B.CrtYd" user "Package Geometry/Place Bound Bottom")
		(35 "F.Fab" user "Ref Des/Assembly Top")
		(33 "B.Fab" user "Ref Des/Assembly Bottom")
	)
	(footprint ""
		(layer "F.Cu")
		(at 173.171358 -388.753604)
		(property "Reference" "C373"
			(at 0 0 0)
			(layer "F.SilkS")
			(hide yes)
			(effects
				(font
					(size 1.27 1.27)
				)
			)
		)
		(property "Value" ""
			(at 0 0 0)
			(layer "F.Fab")
			(effects
				(font
					(size 1.27 1.27)
				)
			)
		)
		(duplicate_pad_numbers_are_jumpers no)
		(fp_line
			(start -0.7874 -0.4064)
			(end 0.7874 -0.4064)
			(stroke
				(width 0.1524)
				(type default)
			)
			(layer "F.SilkS")
		)
		(fp_line
			(start -0.7874 0.4064)
			(end -0.7874 -0.4064)
			(stroke
				(width 0.1524)
				(type default)
			)
			(layer "F.SilkS")
		)
		(fp_line
			(start 0.7874 -0.4064)
			(end 0.7874 0.4064)
			(stroke
				(width 0.1524)
				(type default)
			)
			(layer "F.SilkS")
		)
		(fp_line
			(start 0.7874 0.4064)
			(end -0.7874 0.4064)
			(stroke
				(width 0.1524)
				(type default)
			)
			(layer "F.SilkS")
		)
		(fp_line
			(start -0.67945 -0.305054)
			(end -0.12065 -0.305054)
			(stroke
				(width 0.1)
				(type default)
			)
			(layer "F.Fab")
		)
		(fp_line
			(start -0.67945 0.3048)
			(end -0.67945 -0.305054)
			(stroke
				(width 0.1)
				(type default)
			)
			(layer "F.Fab")
		)
		(fp_line
			(start -0.12065 -0.305054)
			(end -0.12065 -0.2794)
			(stroke
				(width 0.1)
				(type default)
			)
			(layer "F.Fab")
		)
		(fp_line
			(start -0.12065 -0.2794)
			(end 0.12065 -0.2794)
			(stroke
				(width 0.1)
				(type default)
			)
			(layer "F.Fab")
		)
		(fp_line
			(start -0.12065 0.2794)
			(end -0.12065 0.3048)
			(stroke
				(width 0.1)
				(type default)
			)
			(layer "F.Fab")
		)
		(fp_line
			(start -0.12065 0.3048)
			(end -0.67945 0.3048)
			(stroke
				(width 0.1)
				(type default)
			)
			(layer "F.Fab")
		)
		(fp_line
			(start 0.120396 0.2794)
			(end -0.12065 0.2794)
			(stroke
				(width 0.1)
				(type default)
			)
			(layer "F.Fab")
		)
		(fp_line
			(start 0.120396 0.3048)
			(end 0.120396 0.2794)
			(stroke
				(width 0.1)
				(type default)
			)
			(layer "F.Fab")
		)
		(fp_line
			(start 0.12065 -0.3048)
			(end 0.67945 -0.3048)
			(stroke
				(width 0.1)
				(type default)
			)
			(layer "F.Fab")
		)
		(fp_line
			(start 0.12065 -0.2794)
			(end 0.12065 -0.3048)
			(stroke
				(width 0.1)
				(type default)
			)
			(layer "F.Fab")
		)
		(fp_line
			(start 0.67945 -0.3048)
			(end 0.67945 0.3048)
			(stroke
				(width 0.1)
				(type default)
			)
			(layer "F.Fab")
		)
		(fp_line
			(start 0.67945 0.3048)
			(end 0.120396 0.3048)
			(stroke
				(width 0.1)
				(type default)
			)
			(layer "F.Fab")
		)
		(pad "1" smd circle
			(at -0.40005 0)
			(size 0 0)
			(layers "F.Cu" "F.Mask" "F.Paste")
			(net "P1V8_CPU1_RT_1D")
		)
		(pad "2" smd circle
			(at 0.40005 0)
			(size 0 0)
			(layers "F.Cu" "F.Mask" "F.Paste")
			(net "GND")
		)
	)
	(footprint ""
		(layer "F.Cu")
		(at 325.430896 -378.95403 -90)
		(property "Reference" "C907"
			(at 0 0 270)
			(layer "F.SilkS")
			(hide yes)
			(effects
				(font
					(size 1.27 1.27)
				)
			)
		)
		(property "Value" ""
			(at 0 0 270)
			(layer "F.Fab")
			(effects
				(font
					(size 1.27 1.27)
				)
			)
		)
		(duplicate_pad_numbers_are_jumpers no)
		(fp_line
			(start -0.299974 0.150114)
			(end -0.299974 -0.150114)
			(stroke
				(width 0.1)
				(type default)
			)
			(layer "F.Fab")
		)
		(fp_line
			(start 0.299974 0.150114)
			(end -0.299974 0.150114)
			(stroke
				(width 0.1)
				(type default)
			)
			(layer "F.Fab")
		)
		(fp_line
			(start -0.299974 -0.150114)
			(end 0.299974 -0.150114)
			(stroke
				(width 0.1)
				(type default)
			)
			(layer "F.Fab")
		)
		(fp_line
			(start 0.299974 -0.150114)
			(end 0.299974 0.150114)
			(stroke
				(width 0.1)
				(type default)
			)
			(layer "F.Fab")
		)
		(pad "1" smd rect
			(at -0.2667 0 270)
			(size 0.3048 0.381)
			(layers "F.Cu" "F.Mask" "F.Paste")
			(net "P5E_CPU0_P0_TX_C_DP<13>")
		)
		(pad "2" smd rect
			(at 0.2667 0 270)
			(size 0.3048 0.381)
			(layers "F.Cu" "F.Mask" "F.Paste")
			(net "P5E_CPU0_P0_TX_DP<13>")
		)
	)
	(footprint ""
		(layer "F.Cu")
		(at 142.06982 -389.344154 180)
		(property "Reference" "R1434"
			(at 0 0 180)
			(layer "F.SilkS")
			(hide yes)
			(effects
				(font
					(size 1.27 1.27)
				)
			)
		)
		(property "Value" ""
			(at 0 0 180)
			(layer "F.Fab")
			(effects
				(font
					(size 1.27 1.27)
				)
			)
		)
		(duplicate_pad_numbers_are_jumpers no)
		(fp_line
			(start 0.32512 0.175006)
			(end -0.32512 0.175006)
			(stroke
				(width 0.1)
				(type default)
			)
			(layer "F.Fab")
		)
		(fp_line
			(start 0.32512 -0.175006)
			(end 0.32512 0.175006)
			(stroke
				(width 0.1)
				(type default)
			)
			(layer "F.Fab")
		)
		(fp_line
			(start -0.32512 0.175006)
			(end -0.32512 -0.175006)
			(stroke
				(width 0.1)
				(type default)
			)
			(layer "F.Fab")
		)
		(fp_line
			(start -0.32512 -0.175006)
			(end 0.32512 -0.175006)
			(stroke
				(width 0.1)
				(type default)
			)
			(layer "F.Fab")
		)
		(pad "1" smd rect
			(at -0.2667 0 180)
			(size 0.3048 0.381)
			(layers "F.Cu" "F.Mask" "F.Paste")
			(net "P1V8_CPU1_RT_1D")
		)
		(pad "2" smd rect
			(at 0.2667 0)
			(size 0.3048 0.381)
			(layers "F.Cu" "F.Mask" "F.Paste")
			(net "RXDET_BYP_RT_CPU1_P3")
		)
	)
)
